(kicad_pcb
	(version 20260206)
	(generator "pcbnew")
	(generator_version "10.0")
	(general
		(thickness 1.6)
		(legacy_teardrops no)
	)
	(paper "A4")
	(title_block
		(title "04192023_DAF0TMB3IC0_F0TG_MB_C_brd_V02_OCP.brd")
		(comment 1 "Grand Teton / footprints 5792-5797 of 8354")
	)
	(layers
		(0 "F.Cu" signal "TOP")
		(4 "In1.Cu" signal "GND")
		(6 "In2.Cu" signal "IN1")
		(8 "In3.Cu" signal "GND1")
		(10 "In4.Cu" signal "IN2")
		(12 "In5.Cu" signal "GND2")
		(14 "In6.Cu" signal "IN3")
		(16 "In7.Cu" signal "GND3")
		(18 "In8.Cu" signal "VCC")
		(20 "In9.Cu" signal "VCC1")
		(22 "In10.Cu" signal "GND4")
		(24 "In11.Cu" signal "IN4")
		(26 "In12.Cu" signal "GND5")
		(28 "In13.Cu" signal "IN5")
		(30 "In14.Cu" signal "GND6")
		(32 "In15.Cu" signal "IN6")
		(34 "In16.Cu" signal "GND7")
		(2 "B.Cu" signal "BOTTOM")
		(9 "F.Adhes" user "F.Adhesive")
		(11 "B.Adhes" user "B.Adhesive")
		(13 "F.Paste" user "Package Geometry/Pastemask Top")
		(15 "B.Paste" user "Package Geometry/Pastemask Bottom")
		(5 "F.SilkS" user "Ref Des/Silkscreen Top")
		(7 "B.SilkS" user "Ref Des/Silkscreen Bottom")
		(1 "F.Mask" user "Board Geometry/Soldermask Top")
		(3 "B.Mask" user "Board Geometry/Soldermask Bottom")
		(17 "Dwgs.User" user "User.Drawings")
		(19 "Cmts.User" user "User.Comments")
		(21 "Eco1.User" user "User.Eco1")
		(23 "Eco2.User" user "User.Eco2")
		(25 "Edge.Cuts" user "Board Geometry/Outline")
		(27 "Margin" user)
		(31 "F.CrtYd" user "Package Geometry/Place Bound Top")
		(29 "B.CrtYd" user "Package Geometry/Place Bound Bottom")
		(35 "F.Fab" user "Ref Des/Assembly Top")
		(33 "B.Fab" user "Ref Des/Assembly Bottom")
	)
	(footprint ""
		(layer "B.Cu")
		(at 362.988606 -401.624546 180)
		(property "Reference" "R1094"
			(at 0 0 0)
			(layer "B.SilkS")
			(hide yes)
			(effects
				(font
					(size 1.27 1.27)
				)
				(justify mirror)
			)
		)
		(property "Value" ""
			(at 0 0 0)
			(layer "B.Fab")
			(effects
				(font
					(size 1.27 1.27)
				)
				(justify mirror)
			)
		)
		(duplicate_pad_numbers_are_jumpers no)
		(fp_line
			(start 1.2954 0.5842)
			(end 1.2954 -0.5842)
			(stroke
				(width 0.1524)
				(type default)
			)
			(layer "B.SilkS")
		)
		(fp_line
			(start 1.2954 -0.5842)
			(end -1.2954 -0.5842)
			(stroke
				(width 0.1524)
				(type default)
			)
			(layer "B.SilkS")
		)
		(fp_line
			(start -1.2954 0.5842)
			(end 1.2954 0.5842)
			(stroke
				(width 0.1524)
				(type default)
			)
			(layer "B.SilkS")
		)
		(fp_line
			(start -1.2954 -0.5842)
			(end -1.2954 0.5842)
			(stroke
				(width 0.1524)
				(type default)
			)
			(layer "B.SilkS")
		)
		(fp_line
			(start 1.1938 0.4064)
			(end 1.1938 -0.406654)
			(stroke
				(width 0.1)
				(type default)
			)
			(layer "B.Fab")
		)
		(fp_line
			(start 1.1938 -0.406654)
			(end 0.8636 -0.406654)
			(stroke
				(width 0.1)
				(type default)
			)
			(layer "B.Fab")
		)
		(fp_line
			(start 0.8636 0.4572)
			(end 0.8636 0.4318)
			(stroke
				(width 0.1)
				(type default)
			)
			(layer "B.Fab")
		)
		(fp_line
			(start 0.8636 0.4318)
			(end 0.8636 0.4064)
			(stroke
				(width 0.1)
				(type default)
			)
			(layer "B.Fab")
		)
		(fp_line
			(start 0.8636 0.4064)
			(end 1.1938 0.4064)
			(stroke
				(width 0.1)
				(type default)
			)
			(layer "B.Fab")
		)
		(fp_line
			(start 0.8636 -0.406654)
			(end 0.8636 -0.4572)
			(stroke
				(width 0.1)
				(type default)
			)
			(layer "B.Fab")
		)
		(fp_line
			(start 0.8636 -0.4572)
			(end -0.8636 -0.4572)
			(stroke
				(width 0.1)
				(type default)
			)
			(layer "B.Fab")
		)
		(fp_line
			(start -0.8636 0.4572)
			(end 0.8636 0.4572)
			(stroke
				(width 0.1)
				(type default)
			)
			(layer "B.Fab")
		)
		(fp_line
			(start -0.8636 0.4064)
			(end -0.8636 0.4572)
			(stroke
				(width 0.1)
				(type default)
			)
			(layer "B.Fab")
		)
		(fp_line
			(start -0.8636 -0.406654)
			(end -1.1938 -0.406654)
			(stroke
				(width 0.1)
				(type default)
			)
			(layer "B.Fab")
		)
		(fp_line
			(start -0.8636 -0.4572)
			(end -0.8636 -0.406654)
			(stroke
				(width 0.1)
				(type default)
			)
			(layer "B.Fab")
		)
		(fp_line
			(start -1.1938 0.4064)
			(end -0.8636 0.4064)
			(stroke
				(width 0.1)
				(type default)
			)
			(layer "B.Fab")
		)
		(fp_line
			(start -1.1938 -0.406654)
			(end -1.1938 0.4064)
			(stroke
				(width 0.1)
				(type default)
			)
			(layer "B.Fab")
		)
		(pad "1" smd rect
			(at 0.7366 0 90)
			(size 0.7112 0.8128)
			(layers "B.Cu" "B.Mask" "B.Paste")
			(net "P0V9_CPU0_RT_2D")
		)
		(pad "2" smd rect
			(at -0.7366 0 90)
			(size 0.7112 0.8128)
			(layers "B.Cu" "B.Mask" "B.Paste")
			(net "P0V9_CPU0_RT3_2A_2D")
		)
	)
	(footprint ""
		(layer "B.Cu")
		(at 350.596454 -267.52931)
		(property "Reference" "C2205"
			(at 0 0 0)
			(layer "B.SilkS")
			(hide yes)
			(effects
				(font
					(size 1.27 1.27)
				)
				(justify mirror)
			)
		)
		(property "Value" ""
			(at 0 0 0)
			(layer "B.Fab")
			(effects
				(font
					(size 1.27 1.27)
				)
				(justify mirror)
			)
		)
		(duplicate_pad_numbers_are_jumpers no)
		(fp_line
			(start -0.7874 -0.4064)
			(end -0.7874 0.4064)
			(stroke
				(width 0.1524)
				(type default)
			)
			(layer "B.SilkS")
		)
		(fp_line
			(start -0.7874 0.4064)
			(end 0.7874 0.4064)
			(stroke
				(width 0.1524)
				(type default)
			)
			(layer "B.SilkS")
		)
		(fp_line
			(start 0.7874 -0.4064)
			(end -0.7874 -0.4064)
			(stroke
				(width 0.1524)
				(type default)
			)
			(layer "B.SilkS")
		)
		(fp_line
			(start 0.7874 0.4064)
			(end 0.7874 -0.4064)
			(stroke
				(width 0.1524)
				(type default)
			)
			(layer "B.SilkS")
		)
		(fp_line
			(start -0.67945 -0.3048)
			(end -0.67945 0.3048)
			(stroke
				(width 0.1)
				(type default)
			)
			(layer "B.Fab")
		)
		(fp_line
			(start -0.67945 0.3048)
			(end -0.120396 0.3048)
			(stroke
				(width 0.1)
				(type default)
			)
			(layer "B.Fab")
		)
		(fp_line
			(start -0.12065 -0.3048)
			(end -0.67945 -0.3048)
			(stroke
				(width 0.1)
				(type default)
			)
			(layer "B.Fab")
		)
		(fp_line
			(start -0.12065 -0.2794)
			(end -0.12065 -0.3048)
			(stroke
				(width 0.1)
				(type default)
			)
			(layer "B.Fab")
		)
		(fp_line
			(start -0.120396 0.2794)
			(end 0.12065 0.2794)
			(stroke
				(width 0.1)
				(type default)
			)
			(layer "B.Fab")
		)
		(fp_line
			(start -0.120396 0.3048)
			(end -0.120396 0.2794)
			(stroke
				(width 0.1)
				(type default)
			)
			(layer "B.Fab")
		)
		(fp_line
			(start 0.12065 -0.305054)
			(end 0.12065 -0.2794)
			(stroke
				(width 0.1)
				(type default)
			)
			(layer "B.Fab")
		)
		(fp_line
			(start 0.12065 -0.2794)
			(end -0.12065 -0.2794)
			(stroke
				(width 0.1)
				(type default)
			)
			(layer "B.Fab")
		)
		(fp_line
			(start 0.12065 0.2794)
			(end 0.12065 0.3048)
			(stroke
				(width 0.1)
				(type default)
			)
			(layer "B.Fab")
		)
		(fp_line
			(start 0.12065 0.3048)
			(end 0.67945 0.3048)
			(stroke
				(width 0.1)
				(type default)
			)
			(layer "B.Fab")
		)
		(fp_line
			(start 0.67945 -0.305054)
			(end 0.12065 -0.305054)
			(stroke
				(width 0.1)
				(type default)
			)
			(layer "B.Fab")
		)
		(fp_line
			(start 0.67945 0.3048)
			(end 0.67945 -0.305054)
			(stroke
				(width 0.1)
				(type default)
			)
			(layer "B.Fab")
		)
		(pad "1" smd circle
			(at 0.40005 0 180)
			(size 0 0)
			(layers "B.Cu" "B.Mask" "B.Paste")
			(net "PVDDCR_CPU1_P0")
		)
		(pad "2" smd circle
			(at -0.40005 0 180)
			(size 0 0)
			(layers "B.Cu" "B.Mask" "B.Paste")
			(net "GND")
		)
	)
	(footprint ""
		(layer "B.Cu")
		(at 359.740454 -249.87631 90)
		(property "Reference" "C2186"
			(at 0 0 90)
			(layer "B.SilkS")
			(hide yes)
			(effects
				(font
					(size 1.27 1.27)
				)
				(justify mirror)
			)
		)
		(property "Value" ""
			(at 0 0 90)
			(layer "B.Fab")
			(effects
				(font
					(size 1.27 1.27)
				)
				(justify mirror)
			)
		)
		(duplicate_pad_numbers_are_jumpers no)
		(fp_line
			(start 0.7874 -0.4064)
			(end -0.7874 -0.4064)
			(stroke
				(width 0.1524)
				(type default)
			)
			(layer "B.SilkS")
		)
		(fp_line
			(start -0.7874 -0.4064)
			(end -0.7874 0.4064)
			(stroke
				(width 0.1524)
				(type default)
			)
			(layer "B.SilkS")
		)
		(fp_line
			(start 0.7874 0.4064)
			(end 0.7874 -0.4064)
			(stroke
				(width 0.1524)
				(type default)
			)
			(layer "B.SilkS")
		)
		(fp_line
			(start -0.7874 0.4064)
			(end 0.7874 0.4064)
			(stroke
				(width 0.1524)
				(type default)
			)
			(layer "B.SilkS")
		)
		(fp_line
			(start 0.67945 -0.305054)
			(end 0.12065 -0.305054)
			(stroke
				(width 0.1)
				(type default)
			)
			(layer "B.Fab")
		)
		(fp_line
			(start 0.12065 -0.305054)
			(end 0.12065 -0.2794)
			(stroke
				(width 0.1)
				(type default)
			)
			(layer "B.Fab")
		)
		(fp_line
			(start -0.12065 -0.3048)
			(end -0.67945 -0.3048)
			(stroke
				(width 0.1)
				(type default)
			)
			(layer "B.Fab")
		)
		(fp_line
			(start -0.67945 -0.3048)
			(end -0.67945 0.3048)
			(stroke
				(width 0.1)
				(type default)
			)
			(layer "B.Fab")
		)
		(fp_line
			(start 0.12065 -0.2794)
			(end -0.12065 -0.2794)
			(stroke
				(width 0.1)
				(type default)
			)
			(layer "B.Fab")
		)
		(fp_line
			(start -0.12065 -0.2794)
			(end -0.12065 -0.3048)
			(stroke
				(width 0.1)
				(type default)
			)
			(layer "B.Fab")
		)
		(fp_line
			(start 0.12065 0.2794)
			(end 0.12065 0.3048)
			(stroke
				(width 0.1)
				(type default)
			)
			(layer "B.Fab")
		)
		(fp_line
			(start -0.120396 0.2794)
			(end 0.12065 0.2794)
			(stroke
				(width 0.1)
				(type default)
			)
			(layer "B.Fab")
		)
		(fp_line
			(start 0.67945 0.3048)
			(end 0.67945 -0.305054)
			(stroke
				(width 0.1)
				(type default)
			)
			(layer "B.Fab")
		)
		(fp_line
			(start 0.12065 0.3048)
			(end 0.67945 0.3048)
			(stroke
				(width 0.1)
				(type default)
			)
			(layer "B.Fab")
		)
		(fp_line
			(start -0.120396 0.3048)
			(end -0.120396 0.2794)
			(stroke
				(width 0.1)
				(type default)
			)
			(layer "B.Fab")
		)
		(fp_line
			(start -0.67945 0.3048)
			(end -0.120396 0.3048)
			(stroke
				(width 0.1)
				(type default)
			)
			(layer "B.Fab")
		)
		(pad "1" smd circle
			(at 0.40005 0 270)
			(size 0 0)
			(layers "B.Cu" "B.Mask" "B.Paste")
			(net "PVDDCR_CPU0_P0")
		)
		(pad "2" smd circle
			(at -0.40005 0 270)
			(size 0 0)
			(layers "B.Cu" "B.Mask" "B.Paste")
			(net "GND")
		)
	)
	(footprint ""
		(layer "B.Cu")
		(at 164.325554 -349.228156)
		(property "Reference" "PR6"
			(at 0 0 0)
			(layer "B.SilkS")
			(hide yes)
			(effects
				(font
					(size 1.27 1.27)
				)
				(justify mirror)
			)
		)
		(property "Value" ""
			(at 0 0 0)
			(layer "B.Fab")
			(effects
				(font
					(size 1.27 1.27)
				)
				(justify mirror)
			)
		)
		(duplicate_pad_numbers_are_jumpers no)
		(fp_line
			(start -0.7874 -0.4064)
			(end -0.7874 0.4064)
			(stroke
				(width 0.1524)
				(type default)
			)
			(layer "B.SilkS")
		)
		(fp_line
			(start -0.7874 0.4064)
			(end 0.7874 0.4064)
			(stroke
				(width 0.1524)
				(type default)
			)
			(layer "B.SilkS")
		)
		(fp_line
			(start 0.7874 -0.4064)
			(end -0.7874 -0.4064)
			(stroke
				(width 0.1524)
				(type default)
			)
			(layer "B.SilkS")
		)
		(fp_line
			(start 0.7874 0.4064)
			(end 0.7874 -0.4064)
			(stroke
				(width 0.1524)
				(type default)
			)
			(layer "B.SilkS")
		)
		(fp_line
			(start -0.67945 -0.3048)
			(end -0.67945 0.3048)
			(stroke
				(width 0.1)
				(type default)
			)
			(layer "B.Fab")
		)
		(fp_line
			(start -0.67945 0.3048)
			(end -0.120396 0.3048)
			(stroke
				(width 0.1)
				(type default)
			)
			(layer "B.Fab")
		)
		(fp_line
			(start -0.12065 -0.3048)
			(end -0.67945 -0.3048)
			(stroke
				(width 0.1)
				(type default)
			)
			(layer "B.Fab")
		)
		(fp_line
			(start -0.12065 -0.2794)
			(end -0.12065 -0.3048)
			(stroke
				(width 0.1)
				(type default)
			)
			(layer "B.Fab")
		)
		(fp_line
			(start -0.120396 0.2794)
			(end 0.12065 0.2794)
			(stroke
				(width 0.1)
				(type default)
			)
			(layer "B.Fab")
		)
		(fp_line
			(start -0.120396 0.3048)
			(end -0.120396 0.2794)
			(stroke
				(width 0.1)
				(type default)
			)
			(layer "B.Fab")
		)
		(fp_line
			(start 0.12065 -0.305054)
			(end 0.12065 -0.2794)
			(stroke
				(width 0.1)
				(type default)
			)
			(layer "B.Fab")
		)
		(fp_line
			(start 0.12065 -0.2794)
			(end -0.12065 -0.2794)
			(stroke
				(width 0.1)
				(type default)
			)
			(layer "B.Fab")
		)
		(fp_line
			(start 0.12065 0.2794)
			(end 0.12065 0.3048)
			(stroke
				(width 0.1)
				(type default)
			)
			(layer "B.Fab")
		)
		(fp_line
			(start 0.12065 0.3048)
			(end 0.67945 0.3048)
			(stroke
				(width 0.1)
				(type default)
			)
			(layer "B.Fab")
		)
		(fp_line
			(start 0.67945 -0.305054)
			(end 0.12065 -0.305054)
			(stroke
				(width 0.1)
				(type default)
			)
			(layer "B.Fab")
		)
		(fp_line
			(start 0.67945 0.3048)
			(end 0.67945 -0.305054)
			(stroke
				(width 0.1)
				(type default)
			)
			(layer "B.Fab")
		)
		(pad "1" smd circle
			(at 0.40005 0 180)
			(size 0 0)
			(layers "B.Cu" "B.Mask" "B.Paste")
			(net "PVDD11_S3_P1_VMON")
		)
		(pad "2" smd circle
			(at -0.40005 0 180)
			(size 0 0)
			(layers "B.Cu" "B.Mask" "B.Paste")
			(net "GND")
		)
	)
	(footprint ""
		(layer "B.Cu")
		(at 315.585094 -41.13784 90)
		(property "Reference" "R3942"
			(at 0 0 90)
			(layer "B.SilkS")
			(hide yes)
			(effects
				(font
					(size 1.27 1.27)
				)
				(justify mirror)
			)
		)
		(property "Value" ""
			(at 0 0 90)
			(layer "B.Fab")
			(effects
				(font
					(size 1.27 1.27)
				)
				(justify mirror)
			)
		)
		(duplicate_pad_numbers_are_jumpers no)
		(fp_line
			(start 0.7874 -0.4064)
			(end -0.7874 -0.4064)
			(stroke
				(width 0.1524)
				(type default)
			)
			(layer "B.SilkS")
		)
		(fp_line
			(start -0.7874 -0.4064)
			(end -0.7874 0.4064)
			(stroke
				(width 0.1524)
				(type default)
			)
			(layer "B.SilkS")
		)
		(fp_line
			(start 0.7874 0.4064)
			(end 0.7874 -0.4064)
			(stroke
				(width 0.1524)
				(type default)
			)
			(layer "B.SilkS")
		)
		(fp_line
			(start -0.7874 0.4064)
			(end 0.7874 0.4064)
			(stroke
				(width 0.1524)
				(type default)
			)
			(layer "B.SilkS")
		)
		(fp_line
			(start 0.67945 -0.305054)
			(end 0.12065 -0.305054)
			(stroke
				(width 0.1)
				(type default)
			)
			(layer "B.Fab")
		)
		(fp_line
			(start 0.12065 -0.305054)
			(end 0.12065 -0.2794)
			(stroke
				(width 0.1)
				(type default)
			)
			(layer "B.Fab")
		)
		(fp_line
			(start -0.12065 -0.3048)
			(end -0.67945 -0.3048)
			(stroke
				(width 0.1)
				(type default)
			)
			(layer "B.Fab")
		)
		(fp_line
			(start -0.67945 -0.3048)
			(end -0.67945 0.3048)
			(stroke
				(width 0.1)
				(type default)
			)
			(layer "B.Fab")
		)
		(fp_line
			(start 0.12065 -0.2794)
			(end -0.12065 -0.2794)
			(stroke
				(width 0.1)
				(type default)
			)
			(layer "B.Fab")
		)
		(fp_line
			(start -0.12065 -0.2794)
			(end -0.12065 -0.3048)
			(stroke
				(width 0.1)
				(type default)
			)
			(layer "B.Fab")
		)
		(fp_line
			(start 0.12065 0.2794)
			(end 0.12065 0.3048)
			(stroke
				(width 0.1)
				(type default)
			)
			(layer "B.Fab")
		)
		(fp_line
			(start -0.120396 0.2794)
			(end 0.12065 0.2794)
			(stroke
				(width 0.1)
				(type default)
			)
			(layer "B.Fab")
		)
		(fp_line
			(start 0.67945 0.3048)
			(end 0.67945 -0.305054)
			(stroke
				(width 0.1)
				(type default)
			)
			(layer "B.Fab")
		)
		(fp_line
			(start 0.12065 0.3048)
			(end 0.67945 0.3048)
			(stroke
				(width 0.1)
				(type default)
			)
			(layer "B.Fab")
		)
		(fp_line
			(start -0.120396 0.3048)
			(end -0.120396 0.2794)
			(stroke
				(width 0.1)
				(type default)
			)
			(layer "B.Fab")
		)
		(fp_line
			(start -0.67945 0.3048)
			(end -0.120396 0.3048)
			(stroke
				(width 0.1)
				(type default)
			)
			(layer "B.Fab")
		)
		(pad "1" smd rect
			(at 0.40005 0 90)
			(size 0.4572 0.508)
			(layers "B.Cu" "B.Mask" "B.Paste")
			(net "P12V_E1S_0_ISENSE_MPS_TIC")
		)
		(pad "2" smd rect
			(at -0.40005 0 90)
			(size 0.4572 0.508)
			(layers "B.Cu" "B.Mask" "B.Paste")
			(net "P12V_E1S_0_ISENSE_TIC")
		)
	)
	(footprint ""
		(layer "B.Cu")
		(at 152.202642 -76.72324)
		(property "Reference" "PC850"
			(at 0 0 0)
			(layer "B.SilkS")
			(hide yes)
			(effects
				(font
					(size 1.27 1.27)
				)
				(justify mirror)
			)
		)
		(property "Value" ""
			(at 0 0 0)
			(layer "B.Fab")
			(effects
				(font
					(size 1.27 1.27)
				)
				(justify mirror)
			)
		)
		(duplicate_pad_numbers_are_jumpers no)
		(fp_line
			(start -1.524 -0.762)
			(end -1.524 0.762)
			(stroke
				(width 0.1524)
				(type default)
			)
			(layer "B.SilkS")
		)
		(fp_line
			(start -1.524 0.762)
			(end 1.524 0.762)
			(stroke
				(width 0.1524)
				(type default)
			)
			(layer "B.SilkS")
		)
		(fp_line
			(start 1.524 -0.762)
			(end -1.524 -0.762)
			(stroke
				(width 0.1524)
				(type default)
			)
			(layer "B.SilkS")
		)
		(fp_line
			(start 1.524 0.762)
			(end 1.524 -0.762)
			(stroke
				(width 0.1524)
				(type default)
			)
			(layer "B.SilkS")
		)
		(fp_line
			(start -1.1049 -0.724916)
			(end 1.1049 -0.724916)
			(stroke
				(width 0.1)
				(type default)
			)
			(layer "B.Fab")
		)
		(fp_line
			(start -1.1049 0.724916)
			(end -1.1049 -0.724916)
			(stroke
				(width 0.1)
				(type default)
			)
			(layer "B.Fab")
		)
		(fp_line
			(start 1.1049 -0.724916)
			(end 1.1049 0.724916)
			(stroke
				(width 0.1)
				(type default)
			)
			(layer "B.Fab")
		)
		(fp_line
			(start 1.1049 0.724916)
			(end -1.1049 0.724916)
			(stroke
				(width 0.1)
				(type default)
			)
			(layer "B.Fab")
		)
		(pad "1" smd rect
			(at 0.889 0)
			(size 1.016 1.27)
			(layers "B.Cu" "B.Mask" "B.Paste")
			(net "P1V8_AUX")
		)
		(pad "2" smd rect
			(at -0.889 0)
			(size 1.016 1.27)
			(layers "B.Cu" "B.Mask" "B.Paste")
			(net "GND")
		)
	)
)
